M48
INCH,TZ
T01C.02
;EXTENTS: -12.668 -15.298 103.420 96.589  
;LEADER: 12 
;HEADER: 
;CODE  : ASCII 
;FILE  : D:/<user>/gelo/projects/Wiwynn/2017/17301-SA/final board/17301-sa.rou for board D:/<user>/gelo/projects/Wiwynn/2017/17301-SA/final board/#Taaaabl07176.tmp
%
G90
F1
M16
T01
M16
G00X293572Y65571
G40
M15
G01X297372
M16
G00X293572Y108286
G40
M15
G01X297372
M16
G00X328690Y65571
G40
M15
G01X332490
M16
G00X328690Y108286
G40
M15
G01X332490
M16
G40
M30
